# SCM (Grand Teton) — schematic netlist excerpt (pin names and nets, part order shuffled) for the footprints in the layout excerpt that follows; sources: Cadence DE-HDL packaged netlist, KiCad conversion of 12092022_DA0F0TMDCD0_F0T_Management_Board_D_brd_V3_OCP.brd

U27  DT1240E04LP7  DT1240E-04LP-7 IC  pkg U-DFN2510-10_0-5_2-5X1  page 29
  IO1  = USB3_01_FB_TXP
  IO2  = USB3_01_FB_TXN
  VSS1  = GND
  IO3  = USB3_01_FB_RXP
  IO4  = USB3_01_FB_RXN
  NC1  = USB3_01_FB_RXN
  NC2  = USB3_01_FB_RXP
  VSS2  = GND
  NC3  = USB3_01_FB_TXN
  NC4  = USB3_01_FB_TXP

(kicad_pcb
	(version 20260206)
	(generator "pcbnew")
	(generator_version "10.0")
	(general
		(thickness 1.6)
		(legacy_teardrops no)
	)
	(paper "A4")
	(title_block
		(title "12092022_DA0F0TMDCD0_F0T_Management_Board_D_brd_V3_OCP.brd")
		(comment 1 "Grand Teton / footprints 508-508 of 1440")
	)
	(layers
		(0 "F.Cu" signal "TOP")
		(4 "In1.Cu" signal "GND")
		(6 "In2.Cu" signal "IN1")
		(8 "In3.Cu" signal "GND1")
		(10 "In4.Cu" signal "IN2")
		(12 "In5.Cu" signal "VCC")
		(14 "In6.Cu" signal "VCC1")
		(16 "In7.Cu" signal "IN3")
		(18 "In8.Cu" signal "GND2")
		(20 "In9.Cu" signal "IN4")
		(22 "In10.Cu" signal "GND3")
		(2 "B.Cu" signal "BOTTOM")
		(9 "F.Adhes" user "F.Adhesive")
		(11 "B.Adhes" user "B.Adhesive")
		(13 "F.Paste" user "Package Geometry/Pastemask Top")
		(15 "B.Paste" user "Package Geometry/Pastemask Bottom")
		(5 "F.SilkS" user "Ref Des/Silkscreen Top")
		(7 "B.SilkS" user "Ref Des/Silkscreen Bottom")
		(1 "F.Mask" user "Board Geometry/Soldermask Top")
		(3 "B.Mask" user "Board Geometry/Soldermask Bottom")
		(17 "Dwgs.User" user "User.Drawings")
		(19 "Cmts.User" user "User.Comments")
		(21 "Eco1.User" user "User.Eco1")
		(23 "Eco2.User" user "User.Eco2")
		(25 "Edge.Cuts" user "Board Geometry/Outline")
		(27 "Margin" user)
		(31 "F.CrtYd" user "Package Geometry/Place Bound Top")
		(29 "B.CrtYd" user "Package Geometry/Place Bound Bottom")
		(35 "F.Fab" user "Ref Des/Assembly Top")
		(33 "B.Fab" user "Ref Des/Assembly Bottom")
	)
	(footprint ""
		(layer "F.Cu")
		(at 42.346626 -18.1864 90)
		(property "Reference" "U27"
			(at -0.8509 2.015744 90)
			(unlocked yes)
			(layer "F.SilkS")
			(effects
				(font
					(size 0.7874 0.5842)
					(thickness 0.1524)
				)
				(justify left)
			)
		)
		(property "Value" ""
			(at 0 0 90)
			(layer "F.Fab")
			(effects
				(font
					(size 1.27 1.27)
				)
			)
		)
		(duplicate_pad_numbers_are_jumpers no)
		(fp_line
			(start 0.791464 -1.287526)
			(end -0.791464 -1.287526)
			(stroke
				(width 0.1524)
				(type default)
			)
			(layer "F.SilkS")
		)
		(fp_line
			(start -0.791464 -1.287526)
			(end -0.791464 -1.147826)
			(stroke
				(width 0.1524)
				(type default)
			)
			(layer "F.SilkS")
		)
		(fp_line
			(start 0.791464 -1.147826)
			(end 0.791464 -1.287526)
			(stroke
				(width 0.1524)
				(type default)
			)
			(layer "F.SilkS")
		)
		(fp_line
			(start -0.791464 -0.385826)
			(end -0.791464 0.325374)
			(stroke
				(width 0.1524)
				(type default)
			)
			(layer "F.SilkS")
		)
		(fp_line
			(start 0.791464 0.401574)
			(end 0.791464 -0.335026)
			(stroke
				(width 0.1524)
				(type default)
			)
			(layer "F.SilkS")
		)
		(fp_line
			(start -0.791464 1.112774)
			(end -0.791464 1.287526)
			(stroke
				(width 0.1524)
				(type default)
			)
			(layer "F.SilkS")
		)
		(fp_line
			(start 0.791464 1.287526)
			(end 0.791464 1.112774)
			(stroke
				(width 0.1524)
				(type default)
			)
			(layer "F.SilkS")
		)
		(fp_line
			(start -0.791464 1.287526)
			(end 0.791464 1.287526)
			(stroke
				(width 0.1524)
				(type default)
			)
			(layer "F.SilkS")
		)
		(fp_poly
			(pts
				(xy -1.006602 -2.022602) (xy -1.365758 -1.663446) (xy -0.827024 -1.483868)
			)
			(stroke
				(width 0)
				(type default)
			)
			(fill yes)
			(layer "F.SilkS")
		)
		(fp_line
			(start 0.537464 -1.287526)
			(end -0.537464 -1.287526)
			(stroke
				(width 0.1)
				(type default)
			)
			(layer "F.Fab")
		)
		(fp_line
			(start -0.537464 -1.287526)
			(end -0.537464 1.287526)
			(stroke
				(width 0.1)
				(type default)
			)
			(layer "F.Fab")
		)
		(fp_line
			(start 0.537464 1.287526)
			(end 0.537464 -1.287526)
			(stroke
				(width 0.1)
				(type default)
			)
			(layer "F.Fab")
		)
		(fp_line
			(start -0.537464 1.287526)
			(end 0.537464 1.287526)
			(stroke
				(width 0.1)
				(type default)
			)
			(layer "F.Fab")
		)
		(fp_poly
			(pts
				(xy -1.651 -1.253998) (xy -1.651 -0.745998) (xy -1.143 -0.999998)
			)
			(stroke
				(width 0)
				(type default)
			)
			(fill yes)
			(layer "F.Fab")
		)
		(pad "1" smd rect
			(at -0.387604 -0.999998 180)
			(size 0.254 0.635)
			(layers "F.Cu" "F.Mask" "F.Paste")
			(net "USB3_01_FB_TXP")
		)
		(pad "2" smd rect
			(at -0.387604 -0.499872 180)
			(size 0.254 0.635)
			(layers "F.Cu" "F.Mask" "F.Paste")
			(net "USB3_01_FB_TXN")
		)
		(pad "3" smd rect
			(at -0.350012 0 180)
			(size 0.4572 0.6858)
			(layers "F.Cu" "F.Mask" "F.Paste")
			(net "GND")
		)
		(pad "4" smd rect
			(at -0.387604 0.499872 180)
			(size 0.254 0.635)
			(layers "F.Cu" "F.Mask" "F.Paste")
			(net "USB3_01_FB_RXP")
		)
		(pad "5" smd rect
			(at -0.387604 0.999998 180)
			(size 0.254 0.635)
			(layers "F.Cu" "F.Mask" "F.Paste")
			(net "USB3_01_FB_RXN")
		)
		(pad "6" smd rect
			(at 0.387604 0.999998 180)
			(size 0.254 0.635)
			(layers "F.Cu" "F.Mask" "F.Paste")
			(net "USB3_01_FB_RXN")
		)
		(pad "7" smd rect
			(at 0.387604 0.499872 180)
			(size 0.254 0.635)
			(layers "F.Cu" "F.Mask" "F.Paste")
			(net "USB3_01_FB_RXP")
		)
		(pad "8" smd rect
			(at 0.412496 0 180)
			(size 0.4572 0.5842)
			(layers "F.Cu" "F.Mask" "F.Paste")
			(net "GND")
		)
		(pad "9" smd rect
			(at 0.387604 -0.499872 180)
			(size 0.254 0.635)
			(layers "F.Cu" "F.Mask" "F.Paste")
			(net "USB3_01_FB_TXN")
		)
		(pad "10" smd rect
			(at 0.387604 -0.999998 180)
			(size 0.254 0.635)
			(layers "F.Cu" "F.Mask" "F.Paste")
			(net "USB3_01_FB_TXP")
		)
	)
)
